(kicad_pcb
	(version 20260206)
	(generator "pcbnew")
	(generator_version "10.0")
	(general
		(thickness 1.6)
		(legacy_teardrops no)
	)
	(paper "A4")
	(title_block
		(title "peb — Lightning_PEB_BRD.brd")
		(comment 1 "Lightning (Wiwynn / Facebook NVMe JBOF) / footprints 537-542 of 2563")
	)
	(layers
		(0 "F.Cu" signal "TOP")
		(4 "In1.Cu" signal "L2GND")
		(6 "In2.Cu" signal "L3")
		(8 "In3.Cu" signal "L4VCC")
		(10 "In4.Cu" signal "L5VCC")
		(12 "In5.Cu" signal "L6")
		(14 "In6.Cu" signal "L7GND")
		(2 "B.Cu" signal "BOTTOM")
		(9 "F.Adhes" user "F.Adhesive")
		(11 "B.Adhes" user "B.Adhesive")
		(13 "F.Paste" user "Package Geometry/Pastemask Top")
		(15 "B.Paste" user "Package Geometry/Pastemask Bottom")
		(5 "F.SilkS" user "Ref Des/Silkscreen Top")
		(7 "B.SilkS" user "Ref Des/Silkscreen Bottom")
		(1 "F.Mask" user "Board Geometry/Soldermask Top")
		(3 "B.Mask" user "Board Geometry/Soldermask Bottom")
		(17 "Dwgs.User" user "User.Drawings")
		(19 "Cmts.User" user "User.Comments")
		(21 "Eco1.User" user "User.Eco1")
		(23 "Eco2.User" user "User.Eco2")
		(25 "Edge.Cuts" user "Board Geometry/Outline")
		(27 "Margin" user)
		(31 "F.CrtYd" user "Package Geometry/Place Bound Top")
		(29 "B.CrtYd" user "Package Geometry/Place Bound Bottom")
		(35 "F.Fab" user "Ref Des/Assembly Top")
		(33 "B.Fab" user "Ref Des/Assembly Bottom")
	)
	(footprint ""
		(layer "F.Cu")
		(at 78.3082 -84.9122 180)
		(property "Reference" "R477"
			(at 0 0 180)
			(layer "F.SilkS")
			(hide yes)
			(effects
				(font
					(size 1.27 1.27)
				)
			)
		)
		(property "Value" "4K7R2F-GP"
			(at 0.064008 -3.993896 180)
			(unlocked yes)
			(layer "F.Fab")
			(hide yes)
			(effects
				(font
					(size 1.016 1.016)
					(thickness 0.1524)
				)
			)
		)
		(property "Device Type" "R402H16"
			(at 0.064008 -5.517896 180)
			(unlocked yes)
			(layer "F.Fab")
			(hide yes)
			(effects
				(font
					(size 1.016 1.016)
					(thickness 0.1524)
				)
			)
		)
		(duplicate_pad_numbers_are_jumpers no)
		(fp_line
			(start 0.508 -0.9398)
			(end -0.508 -0.9398)
			(stroke
				(width 0.1524)
				(type default)
			)
			(layer "F.SilkS")
		)
		(fp_line
			(start -0.508 -0.9398)
			(end -0.508 0.9398)
			(stroke
				(width 0.1524)
				(type default)
			)
			(layer "F.SilkS")
		)
		(fp_rect
			(start -0.508 0.9398)
			(end 0.508 -0.9398)
			(stroke
				(width 0)
				(type default)
			)
			(fill no)
			(layer "F.CrtYd")
		)
		(fp_rect
			(start -0.508 0.9398)
			(end 0.508 -0.9398)
			(stroke
				(width 0)
				(type default)
			)
			(fill no)
			(layer "F.Fab")
		)
		(pad "1" smd custom
			(at 0 -0.4445 180)
			(size 0.1397 0.1397)
			(layers "F.Cu" "F.Mask" "F.Paste")
			(net "DIVIDER_1_IN")
			(options
				(clearance outline)
				(anchor circle)
			)
			(primitives
				(gr_poly
					(pts
						(arc
							(start -0.1778 -0.2794)
							(mid -0.249642 -0.249642)
							(end -0.2794 -0.1778)
						)
						(arc
							(start -0.2794 0.1778)
							(mid -0.249642 0.249642)
							(end -0.1778 0.2794)
						)
						(arc
							(start 0.1778 0.2794)
							(mid 0.249642 0.249642)
							(end 0.2794 0.1778)
						)
						(arc
							(start 0.2794 -0.1778)
							(mid 0.249642 -0.249642)
							(end 0.1778 -0.2794)
						)
					)
					(width 0)
					(fill yes)
				)
			)
		)
		(pad "2" smd custom
			(at 0 0.4445 180)
			(size 0.1397 0.1397)
			(layers "F.Cu" "F.Mask" "F.Paste")
			(net "DIVIDER_2_IN")
			(options
				(clearance outline)
				(anchor circle)
			)
			(primitives
				(gr_poly
					(pts
						(arc
							(start -0.1778 -0.2794)
							(mid -0.249642 -0.249642)
							(end -0.2794 -0.1778)
						)
						(arc
							(start -0.2794 0.1778)
							(mid -0.249642 0.249642)
							(end -0.1778 0.2794)
						)
						(arc
							(start 0.1778 0.2794)
							(mid 0.249642 0.249642)
							(end 0.2794 0.1778)
						)
						(arc
							(start 0.2794 -0.1778)
							(mid 0.249642 -0.249642)
							(end 0.1778 -0.2794)
						)
					)
					(width 0)
					(fill yes)
				)
			)
		)
	)
	(footprint ""
		(layer "F.Cu")
		(at 125.978412 -208.897474)
		(property "Reference" "R549"
			(at 0 0 0)
			(layer "F.SilkS")
			(hide yes)
			(effects
				(font
					(size 1.27 1.27)
				)
			)
		)
		(property "Value" "10KR2F-2-GP"
			(at 0.064008 -3.993896 0)
			(unlocked yes)
			(layer "F.Fab")
			(hide yes)
			(effects
				(font
					(size 1.016 1.016)
					(thickness 0.1524)
				)
			)
		)
		(property "Device Type" "R402H16"
			(at 0.064008 -5.517896 0)
			(unlocked yes)
			(layer "F.Fab")
			(hide yes)
			(effects
				(font
					(size 1.016 1.016)
					(thickness 0.1524)
				)
			)
		)
		(duplicate_pad_numbers_are_jumpers no)
		(fp_line
			(start -0.508 -0.9398)
			(end -0.508 0.9398)
			(stroke
				(width 0.1524)
				(type default)
			)
			(layer "F.SilkS")
		)
		(fp_line
			(start 0.508 -0.9398)
			(end -0.508 -0.9398)
			(stroke
				(width 0.1524)
				(type default)
			)
			(layer "F.SilkS")
		)
		(fp_rect
			(start -0.508 0.9398)
			(end 0.508 -0.9398)
			(stroke
				(width 0)
				(type default)
			)
			(fill no)
			(layer "F.CrtYd")
		)
		(fp_rect
			(start -0.508 0.9398)
			(end 0.508 -0.9398)
			(stroke
				(width 0)
				(type default)
			)
			(fill no)
			(layer "F.Fab")
		)
		(pad "1" smd custom
			(at 0 -0.4445)
			(size 0.1397 0.1397)
			(layers "F.Cu" "F.Mask" "F.Paste")
			(net "GND")
			(options
				(clearance outline)
				(anchor circle)
			)
			(primitives
				(gr_poly
					(pts
						(arc
							(start -0.1778 -0.2794)
							(mid -0.249642 -0.249642)
							(end -0.2794 -0.1778)
						)
						(arc
							(start -0.2794 0.1778)
							(mid -0.249642 0.249642)
							(end -0.1778 0.2794)
						)
						(arc
							(start 0.1778 0.2794)
							(mid 0.249642 0.249642)
							(end 0.2794 0.1778)
						)
						(arc
							(start 0.2794 -0.1778)
							(mid 0.249642 -0.249642)
							(end 0.1778 -0.2794)
						)
					)
					(width 0)
					(fill yes)
				)
			)
		)
		(pad "2" smd custom
			(at 0 0.4445)
			(size 0.1397 0.1397)
			(layers "F.Cu" "F.Mask" "F.Paste")
			(net "IOEXP2_AD0")
			(options
				(clearance outline)
				(anchor circle)
			)
			(primitives
				(gr_poly
					(pts
						(arc
							(start -0.1778 -0.2794)
							(mid -0.249642 -0.249642)
							(end -0.2794 -0.1778)
						)
						(arc
							(start -0.2794 0.1778)
							(mid -0.249642 0.249642)
							(end -0.1778 0.2794)
						)
						(arc
							(start 0.1778 0.2794)
							(mid 0.249642 0.249642)
							(end 0.2794 0.1778)
						)
						(arc
							(start 0.2794 -0.1778)
							(mid 0.249642 -0.249642)
							(end 0.1778 -0.2794)
						)
					)
					(width 0)
					(fill yes)
				)
			)
		)
	)
	(footprint ""
		(layer "F.Cu")
		(at 43.379136 -46.783244)
		(property "Reference" "L8"
			(at 0 0 0)
			(layer "F.SilkS")
			(hide yes)
			(effects
				(font
					(size 1.27 1.27)
				)
			)
		)
		(property "Value" "DLW21HN900SQ2LGP-U"
			(at -0.0889 -2.7813 0)
			(unlocked yes)
			(layer "F.Fab")
			(hide yes)
			(effects
				(font
					(size 1.016 1.016)
					(thickness 0.1524)
				)
			)
		)
		(property "Device Type" "L2012-4P-1MH40"
			(at -0.0889 -4.3053 0)
			(unlocked yes)
			(layer "F.Fab")
			(hide yes)
			(effects
				(font
					(size 1.016 1.016)
					(thickness 0.1524)
				)
			)
		)
		(duplicate_pad_numbers_are_jumpers no)
		(fp_line
			(start -1.5494 -1.0668)
			(end 1.5494 -1.0668)
			(stroke
				(width 0.1524)
				(type default)
			)
			(layer "F.SilkS")
		)
		(fp_line
			(start -1.5494 1.0668)
			(end -1.5494 -1.0668)
			(stroke
				(width 0.1524)
				(type default)
			)
			(layer "F.SilkS")
		)
		(fp_line
			(start 1.0668 1.1811)
			(end 0.6858 1.1811)
			(stroke
				(width 0.3302)
				(type default)
			)
			(layer "F.SilkS")
		)
		(fp_line
			(start 1.5494 -1.0668)
			(end 1.5494 1.0668)
			(stroke
				(width 0.1524)
				(type default)
			)
			(layer "F.SilkS")
		)
		(fp_line
			(start 1.5494 1.0668)
			(end -1.5494 1.0668)
			(stroke
				(width 0.1524)
				(type default)
			)
			(layer "F.SilkS")
		)
		(fp_poly
			(pts
				(xy 1.500124 1.768856) (xy 0.230124 1.768856) (xy 0.865124 1.133856)
			)
			(stroke
				(width 0)
				(type default)
			)
			(fill yes)
			(layer "F.SilkS")
		)
		(fp_rect
			(start -1.0033 0.5969)
			(end 1.0033 -0.5969)
			(stroke
				(width 0)
				(type default)
			)
			(fill no)
			(layer "F.CrtYd")
		)
		(fp_poly
			(pts
				(xy -1.8034 1.3208) (xy -1.8034 -1.3208) (xy 1.8034 -1.3208) (xy 1.8034 0.0508) (xy 1.0033 0.0508)
				(xy 1.0033 -0.5969) (xy -1.0033 -0.5969) (xy -1.0033 0.5969) (xy 1.0033 0.5969) (xy 1.0033 0.0762)
				(xy 1.8034 0.0762) (xy 1.8034 1.3208)
			)
			(stroke
				(width 0)
				(type default)
			)
			(fill no)
			(layer "F.CrtYd")
		)
		(fp_rect
			(start -1.8034 1.3208)
			(end 1.8034 -1.3208)
			(stroke
				(width 0)
				(type default)
			)
			(fill no)
			(layer "F.Fab")
		)
		(pad "1" smd rect
			(at 0.8382 0.4826)
			(size 0.9144 0.6604)
			(layers "F.Cu" "F.Mask" "F.Paste")
			(net "USB_DP_R")
		)
		(pad "2" smd rect
			(at -0.8382 0.4826)
			(size 0.9144 0.6604)
			(layers "F.Cu" "F.Mask" "F.Paste")
			(net "USB_P1_F_DP1")
		)
		(pad "3" smd rect
			(at -0.8382 -0.4826)
			(size 0.9144 0.6604)
			(layers "F.Cu" "F.Mask" "F.Paste")
			(net "USB_P1_F_DN1")
		)
		(pad "4" smd rect
			(at 0.8382 -0.4826)
			(size 0.9144 0.6604)
			(layers "F.Cu" "F.Mask" "F.Paste")
			(net "USB_DN_R")
		)
		(zone
			(layer "F.Cu")
			(hatch none 0.5)
			(connect_pads
				(clearance 0)
			)
			(min_thickness 0.25)
			(keepout
				(tracks not_allowed)
				(vias allowed)
				(pads allowed)
				(copperpour not_allowed)
				(footprints allowed)
			)
			(placement
				(enabled no)
				(sheetname "")
			)
			(fill
				(thermal_gap 0.5)
				(thermal_bridge_width 0.5)
				(island_removal_mode 0)
			)
			(polygon
				(pts
					(xy 42.998136 -45.970444) (xy 42.998136 -46.630844) (xy 42.083736 -46.630844) (xy 42.083736 -46.935644)
					(xy 42.998136 -46.935644) (xy 42.998136 -47.596044) (xy 43.760136 -47.596044) (xy 43.760136 -46.935644)
					(xy 44.674536 -46.935644) (xy 44.674536 -46.630844) (xy 43.760136 -46.630844) (xy 43.760136 -45.970444)
				)
			)
		)
		(zone
			(layer "F.Cu")
			(hatch none 0.5)
			(connect_pads
				(clearance 0)
			)
			(min_thickness 0.25)
			(keepout
				(tracks allowed)
				(vias not_allowed)
				(pads allowed)
				(copperpour not_allowed)
				(footprints allowed)
			)
			(placement
				(enabled no)
				(sheetname "")
			)
			(fill
				(thermal_gap 0.5)
				(thermal_bridge_width 0.5)
				(island_removal_mode 0)
			)
			(polygon
				(pts
					(xy 42.998136 -45.970444) (xy 42.998136 -46.630844) (xy 42.083736 -46.630844) (xy 42.083736 -46.935644)
					(xy 42.998136 -46.935644) (xy 42.998136 -47.596044) (xy 43.760136 -47.596044) (xy 43.760136 -46.935644)
					(xy 44.674536 -46.935644) (xy 44.674536 -46.630844) (xy 43.760136 -46.630844) (xy 43.760136 -45.970444)
				)
			)
		)
	)
	(footprint ""
		(layer "F.Cu")
		(at 273.699986 -1.397 -90)
		(property "Reference" "R2916"
			(at 0 0 270)
			(layer "F.SilkS")
			(hide yes)
			(effects
				(font
					(size 1.27 1.27)
				)
			)
		)
		(property "Value" "0R2J-2-GP"
			(at 0.064008 -3.993896 270)
			(unlocked yes)
			(layer "F.Fab")
			(hide yes)
			(effects
				(font
					(size 1.016 1.016)
					(thickness 0.1524)
				)
			)
		)
		(property "Device Type" "R402H16"
			(at 0.064008 -5.517896 270)
			(unlocked yes)
			(layer "F.Fab")
			(hide yes)
			(effects
				(font
					(size 1.016 1.016)
					(thickness 0.1524)
				)
			)
		)
		(duplicate_pad_numbers_are_jumpers no)
		(fp_line
			(start -0.508 -0.9398)
			(end -0.508 0.9398)
			(stroke
				(width 0.1524)
				(type default)
			)
			(layer "F.SilkS")
		)
		(fp_line
			(start 0.508 -0.9398)
			(end -0.508 -0.9398)
			(stroke
				(width 0.1524)
				(type default)
			)
			(layer "F.SilkS")
		)
		(fp_rect
			(start -0.508 0.9398)
			(end 0.508 -0.9398)
			(stroke
				(width 0)
				(type default)
			)
			(fill no)
			(layer "F.CrtYd")
		)
		(fp_rect
			(start -0.508 0.9398)
			(end 0.508 -0.9398)
			(stroke
				(width 0)
				(type default)
			)
			(fill no)
			(layer "F.Fab")
		)
		(pad "1" smd custom
			(at 0 -0.4445 270)
			(size 0.1397 0.1397)
			(layers "F.Cu" "F.Mask" "F.Paste")
			(net "BMC_I2C13_MINI7_SDA")
			(options
				(clearance outline)
				(anchor circle)
			)
			(primitives
				(gr_poly
					(pts
						(arc
							(start -0.1778 -0.2794)
							(mid -0.249642 -0.249642)
							(end -0.2794 -0.1778)
						)
						(arc
							(start -0.2794 0.1778)
							(mid -0.249642 0.249642)
							(end -0.1778 0.2794)
						)
						(arc
							(start 0.1778 0.2794)
							(mid 0.249642 0.249642)
							(end 0.2794 0.1778)
						)
						(arc
							(start 0.2794 -0.1778)
							(mid 0.249642 -0.249642)
							(end 0.1778 -0.2794)
						)
					)
					(width 0)
					(fill yes)
				)
			)
		)
		(pad "2" smd custom
			(at 0 0.4445 270)
			(size 0.1397 0.1397)
			(layers "F.Cu" "F.Mask" "F.Paste")
			(net "8644_CBL_PRSNT_R_7")
			(options
				(clearance outline)
				(anchor circle)
			)
			(primitives
				(gr_poly
					(pts
						(arc
							(start -0.1778 -0.2794)
							(mid -0.249642 -0.249642)
							(end -0.2794 -0.1778)
						)
						(arc
							(start -0.2794 0.1778)
							(mid -0.249642 0.249642)
							(end -0.1778 0.2794)
						)
						(arc
							(start 0.1778 0.2794)
							(mid 0.249642 0.249642)
							(end 0.2794 0.1778)
						)
						(arc
							(start 0.2794 -0.1778)
							(mid 0.249642 -0.249642)
							(end 0.1778 -0.2794)
						)
					)
					(width 0)
					(fill yes)
				)
			)
		)
	)
	(footprint ""
		(layer "F.Cu")
		(at 326.807322 -33.45942)
		(property "Reference" "C51"
			(at 0 0 0)
			(layer "F.SilkS")
			(hide yes)
			(effects
				(font
					(size 1.27 1.27)
				)
			)
		)
		(property "Value" "SCD22U10V2KX-1GP"
			(at 1.1811 -2.7051 0)
			(unlocked yes)
			(layer "F.Fab")
			(hide yes)
			(effects
				(font
					(size 1.016 1.016)
					(thickness 0.1524)
				)
			)
		)
		(property "Device Type" "C402H22"
			(at 1.1811 -4.2291 0)
			(unlocked yes)
			(layer "F.Fab")
			(hide yes)
			(effects
				(font
					(size 1.016 1.016)
					(thickness 0.1524)
				)
			)
		)
		(duplicate_pad_numbers_are_jumpers no)
		(fp_rect
			(start -0.4318 0.9525)
			(end 0.4318 -0.9525)
			(stroke
				(width 0)
				(type default)
			)
			(fill no)
			(layer "F.CrtYd")
		)
		(fp_rect
			(start -0.4318 0.9525)
			(end 0.4318 -0.9525)
			(stroke
				(width 0)
				(type default)
			)
			(fill no)
			(layer "F.Fab")
		)
		(pad "1" smd custom
			(at 0 -0.4445)
			(size 0.1524 0.1524)
			(layers "F.Cu" "F.Mask" "F.Paste")
			(net "PCIE_TX_CAP_N14")
			(options
				(clearance outline)
				(anchor circle)
			)
			(primitives
				(gr_poly
					(pts
						(arc
							(start 0.3048 -0.2032)
							(mid 0.275042 -0.275042)
							(end 0.2032 -0.3048)
						)
						(arc
							(start -0.2032 -0.3048)
							(mid -0.275042 -0.275042)
							(end -0.3048 -0.2032)
						)
						(arc
							(start -0.3048 0.2032)
							(mid -0.275042 0.275042)
							(end -0.2032 0.3048)
						)
						(arc
							(start 0.2032 0.3048)
							(mid 0.275042 0.275042)
							(end 0.3048 0.2032)
						)
					)
					(width 0)
					(fill yes)
				)
			)
		)
		(pad "2" smd custom
			(at 0 0.4445)
			(size 0.1524 0.1524)
			(layers "F.Cu" "F.Mask" "F.Paste")
			(net "PCIE_TX_N14")
			(options
				(clearance outline)
				(anchor circle)
			)
			(primitives
				(gr_poly
					(pts
						(arc
							(start 0.3048 -0.2032)
							(mid 0.275042 -0.275042)
							(end 0.2032 -0.3048)
						)
						(arc
							(start -0.2032 -0.3048)
							(mid -0.275042 -0.275042)
							(end -0.3048 -0.2032)
						)
						(arc
							(start -0.3048 0.2032)
							(mid -0.275042 0.275042)
							(end -0.2032 0.3048)
						)
						(arc
							(start 0.2032 0.3048)
							(mid 0.275042 0.275042)
							(end 0.3048 0.2032)
						)
					)
					(width 0)
					(fill yes)
				)
			)
		)
	)
	(footprint ""
		(layer "F.Cu")
		(at 160.528 -95.9104 180)
		(property "Reference" "R89"
			(at 0 0 180)
			(layer "F.SilkS")
			(hide yes)
			(effects
				(font
					(size 1.27 1.27)
				)
			)
		)
		(property "Value" "0R2J-2-GP"
			(at 0.064008 -3.993896 180)
			(unlocked yes)
			(layer "F.Fab")
			(hide yes)
			(effects
				(font
					(size 1.016 1.016)
					(thickness 0.1524)
				)
			)
		)
		(property "Device Type" "R402H16"
			(at 0.064008 -5.517896 180)
			(unlocked yes)
			(layer "F.Fab")
			(hide yes)
			(effects
				(font
					(size 1.016 1.016)
					(thickness 0.1524)
				)
			)
		)
		(duplicate_pad_numbers_are_jumpers no)
		(fp_line
			(start 0.508 -0.9398)
			(end -0.508 -0.9398)
			(stroke
				(width 0.1524)
				(type default)
			)
			(layer "F.SilkS")
		)
		(fp_line
			(start -0.508 -0.9398)
			(end -0.508 0.9398)
			(stroke
				(width 0.1524)
				(type default)
			)
			(layer "F.SilkS")
		)
		(fp_rect
			(start -0.508 0.9398)
			(end 0.508 -0.9398)
			(stroke
				(width 0)
				(type default)
			)
			(fill no)
			(layer "F.CrtYd")
		)
		(fp_rect
			(start -0.508 0.9398)
			(end 0.508 -0.9398)
			(stroke
				(width 0)
				(type default)
			)
			(fill no)
			(layer "F.Fab")
		)
		(pad "1" smd custom
			(at 0 -0.4445 180)
			(size 0.1397 0.1397)
			(layers "F.Cu" "F.Mask" "F.Paste")
			(net "CLKGEN_OE3_R")
			(options
				(clearance outline)
				(anchor circle)
			)
			(primitives
				(gr_poly
					(pts
						(arc
							(start -0.1778 -0.2794)
							(mid -0.249642 -0.249642)
							(end -0.2794 -0.1778)
						)
						(arc
							(start -0.2794 0.1778)
							(mid -0.249642 0.249642)
							(end -0.1778 0.2794)
						)
						(arc
							(start 0.1778 0.2794)
							(mid 0.249642 0.249642)
							(end 0.2794 0.1778)
						)
						(arc
							(start 0.2794 -0.1778)
							(mid 0.249642 -0.249642)
							(end 0.1778 -0.2794)
						)
					)
					(width 0)
					(fill yes)
				)
			)
		)
		(pad "2" smd custom
			(at 0 0.4445 180)
			(size 0.1397 0.1397)
			(layers "F.Cu" "F.Mask" "F.Paste")
			(net "CLKGEN_OE3")
			(options
				(clearance outline)
				(anchor circle)
			)
			(primitives
				(gr_poly
					(pts
						(arc
							(start -0.1778 -0.2794)
							(mid -0.249642 -0.249642)
							(end -0.2794 -0.1778)
						)
						(arc
							(start -0.2794 0.1778)
							(mid -0.249642 0.249642)
							(end -0.1778 0.2794)
						)
						(arc
							(start 0.1778 0.2794)
							(mid 0.249642 0.249642)
							(end 0.2794 0.1778)
						)
						(arc
							(start 0.2794 -0.1778)
							(mid 0.249642 -0.249642)
							(end 0.1778 -0.2794)
						)
					)
					(width 0)
					(fill yes)
				)
			)
		)
	)
)
